# S9S_MB_2U (Grand Teton) — schematic netlist excerpt (pin names and nets, part order shuffled) for the footprints in the layout excerpt that follows; sources: Cadence DE-HDL packaged netlist, KiCad conversion of 03242023_DA0F0TMBIJ0_F0T_Motherboard_J_brd_V01_OCP.brd

Q16  MOSFET_NCH_DUAL  PJT138K IC  pkg SOT363XD  page 235
  S1  = GND
  G1  = FM_SMB_PEHPCPU1_PCIE_ALERT_R_N
  D2  = FM_PEHPCPU1_ALERT_N
  S2  = GND
  G2  = FM_SMB_CPU1_ALERT_R1
  D1  = FM_SMB_CPU1_ALERT_R1

C2349  Q_CAP_DIFFBUS  DIFF BUS_0.33UF 6.3V 10% X6S  pkg C0402  page 169 : \1\ = USB3_PCH_RX_DP<4> ; \2\ = USB3_PCH_RX_C_DP<4>

(kicad_pcb
	(version 20260206)
	(generator "pcbnew")
	(generator_version "10.0")
	(general
		(thickness 1.6)
		(legacy_teardrops no)
	)
	(paper "A4")
	(title_block
		(title "03242023_DA0F0TMBIJ0_F0T_Motherboard_J_brd_V01_OCP.brd")
		(comment 1 "Grand Teton / footprints 5949-5950 of 6105")
	)
	(layers
		(0 "F.Cu" signal "TOP")
		(4 "In1.Cu" signal "GND")
		(6 "In2.Cu" signal "IN1")
		(8 "In3.Cu" signal "GND1")
		(10 "In4.Cu" signal "IN2")
		(12 "In5.Cu" signal "GND2")
		(14 "In6.Cu" signal "IN3")
		(16 "In7.Cu" signal "GND3")
		(18 "In8.Cu" signal "VCC")
		(20 "In9.Cu" signal "VCC1")
		(22 "In10.Cu" signal "GND4")
		(24 "In11.Cu" signal "IN4")
		(26 "In12.Cu" signal "GND5")
		(28 "In13.Cu" signal "IN5")
		(30 "In14.Cu" signal "GND6")
		(32 "In15.Cu" signal "IN6")
		(34 "In16.Cu" signal "GND7")
		(2 "B.Cu" signal "BOTTOM")
		(9 "F.Adhes" user "F.Adhesive")
		(11 "B.Adhes" user "B.Adhesive")
		(13 "F.Paste" user "Package Geometry/Pastemask Top")
		(15 "B.Paste" user "Package Geometry/Pastemask Bottom")
		(5 "F.SilkS" user "Ref Des/Silkscreen Top")
		(7 "B.SilkS" user "Ref Des/Silkscreen Bottom")
		(1 "F.Mask" user "Board Geometry/Soldermask Top")
		(3 "B.Mask" user "Board Geometry/Soldermask Bottom")
		(17 "Dwgs.User" user "User.Drawings")
		(19 "Cmts.User" user "User.Comments")
		(21 "Eco1.User" user "User.Eco1")
		(23 "Eco2.User" user "User.Eco2")
		(25 "Edge.Cuts" user "Board Geometry/Outline")
		(27 "Margin" user)
		(31 "F.CrtYd" user "Package Geometry/Place Bound Top")
		(29 "B.CrtYd" user "Package Geometry/Place Bound Bottom")
		(35 "F.Fab" user "Ref Des/Assembly Top")
		(33 "B.Fab" user "Ref Des/Assembly Bottom")
	)
	(footprint ""
		(layer "B.Cu")
		(at 131.74726 -28.20924)
		(property "Reference" "C2349"
			(at 0 0 0)
			(layer "B.SilkS")
			(hide yes)
			(effects
				(font
					(size 1.27 1.27)
				)
				(justify mirror)
			)
		)
		(property "Value" ""
			(at 0 0 0)
			(layer "B.Fab")
			(effects
				(font
					(size 1.27 1.27)
				)
				(justify mirror)
			)
		)
		(duplicate_pad_numbers_are_jumpers no)
		(fp_line
			(start -0.40005 0.4064)
			(end 0.40005 0.4064)
			(stroke
				(width 0.1524)
				(type default)
			)
			(layer "B.SilkS")
		)
		(fp_line
			(start 0.40005 -0.4064)
			(end -0.40005 -0.4064)
			(stroke
				(width 0.1524)
				(type default)
			)
			(layer "B.SilkS")
		)
		(fp_line
			(start -0.6858 -0.3048)
			(end -0.6858 0.3048)
			(stroke
				(width 0.1)
				(type default)
			)
			(layer "B.Fab")
		)
		(fp_line
			(start -0.6858 0.3048)
			(end -0.1016 0.3048)
			(stroke
				(width 0.1)
				(type default)
			)
			(layer "B.Fab")
		)
		(fp_line
			(start -0.1016 -0.3048)
			(end -0.6858 -0.3048)
			(stroke
				(width 0.1)
				(type default)
			)
			(layer "B.Fab")
		)
		(fp_line
			(start -0.1016 -0.2794)
			(end -0.1016 -0.3048)
			(stroke
				(width 0.1)
				(type default)
			)
			(layer "B.Fab")
		)
		(fp_line
			(start -0.1016 0.2794)
			(end 0.1016 0.2794)
			(stroke
				(width 0.1)
				(type default)
			)
			(layer "B.Fab")
		)
		(fp_line
			(start -0.1016 0.3048)
			(end -0.1016 0.2794)
			(stroke
				(width 0.1)
				(type default)
			)
			(layer "B.Fab")
		)
		(fp_line
			(start 0.1016 -0.3048)
			(end 0.1016 -0.2794)
			(stroke
				(width 0.1)
				(type default)
			)
			(layer "B.Fab")
		)
		(fp_line
			(start 0.1016 -0.2794)
			(end -0.1016 -0.2794)
			(stroke
				(width 0.1)
				(type default)
			)
			(layer "B.Fab")
		)
		(fp_line
			(start 0.1016 0.2794)
			(end 0.1016 0.3048)
			(stroke
				(width 0.1)
				(type default)
			)
			(layer "B.Fab")
		)
		(fp_line
			(start 0.1016 0.3048)
			(end 0.6858 0.3048)
			(stroke
				(width 0.1)
				(type default)
			)
			(layer "B.Fab")
		)
		(fp_line
			(start 0.6858 -0.3048)
			(end 0.1016 -0.3048)
			(stroke
				(width 0.1)
				(type default)
			)
			(layer "B.Fab")
		)
		(fp_line
			(start 0.6858 0.3048)
			(end 0.6858 -0.3048)
			(stroke
				(width 0.1)
				(type default)
			)
			(layer "B.Fab")
		)
		(pad "1" smd rect
			(at 0.40005 0)
			(size 0.4572 0.508)
			(layers "B.Cu" "B.Mask" "B.Paste")
			(net "USB3_PCH_RX_DP<4>")
		)
		(pad "2" smd rect
			(at -0.40005 0)
			(size 0.4572 0.508)
			(layers "B.Cu" "B.Mask" "B.Paste")
			(net "USB3_PCH_RX_C_DP<4>")
		)
		(zone
			(layer "In16.Cu")
			(hatch none 0.5)
			(connect_pads
				(clearance 0)
			)
			(min_thickness 0.25)
			(keepout
				(tracks not_allowed)
				(vias allowed)
				(pads allowed)
				(copperpour not_allowed)
				(footprints allowed)
			)
			(placement
				(enabled no)
				(sheetname "")
			)
			(fill
				(thermal_gap 0.5)
				(thermal_bridge_width 0.5)
				(island_removal_mode 0)
			)
			(polygon
				(pts
					(xy 131.62661 -27.90444) (xy 131.06781 -27.90444) (xy 131.06781 -28.51404) (xy 131.62661 -28.51404)
				)
			)
		)
		(zone
			(layer "In16.Cu")
			(hatch none 0.5)
			(connect_pads
				(clearance 0)
			)
			(min_thickness 0.25)
			(keepout
				(tracks not_allowed)
				(vias allowed)
				(pads allowed)
				(copperpour not_allowed)
				(footprints allowed)
			)
			(placement
				(enabled no)
				(sheetname "")
			)
			(fill
				(thermal_gap 0.5)
				(thermal_bridge_width 0.5)
				(island_removal_mode 0)
			)
			(polygon
				(pts
					(xy 132.42671 -27.90444) (xy 131.86791 -27.90444) (xy 131.86791 -28.51404) (xy 132.42671 -28.51404)
				)
			)
		)
	)
	(footprint ""
		(layer "B.Cu")
		(at 89.343484 -181.450488 90)
		(property "Reference" "Q16"
			(at 0.79121 4.346956 0)
			(unlocked yes)
			(layer "B.SilkS")
			(effects
				(font
					(size 0.7874 0.5842)
					(thickness 0.1524)
				)
				(justify left mirror)
			)
		)
		(property "Value" ""
			(at 0 0 90)
			(layer "B.Fab")
			(effects
				(font
					(size 1.27 1.27)
				)
				(justify mirror)
			)
		)
		(duplicate_pad_numbers_are_jumpers no)
		(fp_line
			(start 1.332738 -1.100074)
			(end 0.4826 -1.100074)
			(stroke
				(width 0.1524)
				(type default)
			)
			(layer "B.SilkS")
		)
		(fp_line
			(start 0.4826 -1.100074)
			(end 0 -0.541274)
			(stroke
				(width 0.1524)
				(type default)
			)
			(layer "B.SilkS")
		)
		(fp_line
			(start -0.4826 -1.100074)
			(end -1.332738 -1.100074)
			(stroke
				(width 0.1524)
				(type default)
			)
			(layer "B.SilkS")
		)
		(fp_line
			(start -1.332738 -1.100074)
			(end -1.332738 1.100074)
			(stroke
				(width 0.1524)
				(type default)
			)
			(layer "B.SilkS")
		)
		(fp_line
			(start 0 -0.541274)
			(end -0.4826 -1.100074)
			(stroke
				(width 0.1524)
				(type default)
			)
			(layer "B.SilkS")
		)
		(fp_line
			(start 1.332738 1.100074)
			(end 1.332738 -1.100074)
			(stroke
				(width 0.1524)
				(type default)
			)
			(layer "B.SilkS")
		)
		(fp_line
			(start -1.332738 1.100074)
			(end 1.332738 1.100074)
			(stroke
				(width 0.1524)
				(type default)
			)
			(layer "B.SilkS")
		)
		(fp_poly
			(pts
				(xy 1.50749 -2.152904) (xy 1.156462 -1.450848) (xy 0.805434 -2.152904)
			)
			(stroke
				(width 0)
				(type default)
			)
			(fill yes)
			(layer "B.SilkS")
		)
		(fp_line
			(start 0.674878 -1.100074)
			(end -0.674878 -1.100074)
			(stroke
				(width 0.1)
				(type default)
			)
			(layer "B.Fab")
		)
		(fp_line
			(start -0.674878 -1.100074)
			(end -0.674878 1.100074)
			(stroke
				(width 0.1)
				(type default)
			)
			(layer "B.Fab")
		)
		(fp_line
			(start 0.674878 1.100074)
			(end 0.674878 -1.100074)
			(stroke
				(width 0.1)
				(type default)
			)
			(layer "B.Fab")
		)
		(fp_line
			(start -0.674878 1.100074)
			(end 0.674878 1.100074)
			(stroke
				(width 0.1)
				(type default)
			)
			(layer "B.Fab")
		)
		(fp_poly
			(pts
				(xy 2.2352 -0.298958) (xy 2.2352 -1.001014) (xy 1.533144 -0.649986)
			)
			(stroke
				(width 0)
				(type default)
			)
			(fill yes)
			(layer "B.Fab")
		)
		(pad "1" smd rect
			(at 0.94996 -0.649986 180)
			(size 0.4318 0.508)
			(layers "B.Cu" "B.Mask" "B.Paste")
			(net "GND")
		)
		(pad "2" smd rect
			(at 0.94996 0 180)
			(size 0.4318 0.508)
			(layers "B.Cu" "B.Mask" "B.Paste")
			(net "FM_SMB_PEHPCPU1_PCIE_ALERT_R_N")
		)
		(pad "3" smd rect
			(at 0.94996 0.649986 180)
			(size 0.4318 0.508)
			(layers "B.Cu" "B.Mask" "B.Paste")
			(net "FM_PEHPCPU1_ALERT_N")
		)
		(pad "4" smd rect
			(at -0.94996 0.649986 180)
			(size 0.4318 0.508)
			(layers "B.Cu" "B.Mask" "B.Paste")
			(net "GND")
		)
		(pad "5" smd rect
			(at -0.94996 0 180)
			(size 0.4318 0.508)
			(layers "B.Cu" "B.Mask" "B.Paste")
			(net "FM_SMB_CPU1_ALERT_R1")
		)
		(pad "6" smd rect
			(at -0.94996 -0.649986 180)
			(size 0.4318 0.508)
			(layers "B.Cu" "B.Mask" "B.Paste")
			(net "FM_SMB_CPU1_ALERT_R1")
		)
	)
)
